Altium Designer Pick and Place Locations
C:\Users\<user>\Desktop\WorkNotes\Projects\PTP\TimeCardNPI\HackDesign\WIP\ECAD\Project Outputs for Timingcard_PROJECT\Pick Place for TimeCard-DC-V9_EXP.csv

========================================================================================================================
File Design Information:

Date:       28/08/23
Time:       18:24
Revision:   Not in VersionControl
Variant:    No variations
Units used: mil

"Designator","Comment","Layer","Footprint","Center-X(mil)","Center-Y(mil)","Rotation","Description"
"R186","10K_1%_0402","BottomLayer","RESC1005X40X25LL05T10","454.014","-1543.654","0",""
"R185","10K_1%_0402","BottomLayer","RESC1005X40X25NL10T10","4437.008","-1543.307","0",""
"R184","10K_1%_0402","BottomLayer","RESC1005X40X25NL10T10","4373.027","-1460.630","270",""
"R183","20K_1%_0402","BottomLayer","RESC1005X40X25NL10T10","4417.323","-1460.630","270",""
"U34","TPS2116DRLR","BottomLayer","IC_TPS2116","5677.823","-2795.343","0","1.6-V to 5.5-V, 40-m?, 2.5-A, low-IQ, priority power multiplexer 8-SOT-5X3 -40 to 125"
"U32","TPS2116DRLR","BottomLayer","IC_TPS2116","5338.779","-2746.850","180","1.6-V to 5.5-V, 40-m?, 2.5-A, low-IQ, priority power multiplexer 8-SOT-5X3 -40 to 125"
"U33","NCP176AMX330TCG","BottomLayer","FP-711AT-MFG","5896.524","-2799.924","0","IC REG LINEAR 3.3V 500MA 6XDFN"
"R182","10K_5%_0402","BottomLayer","RESC1005X40X25ML05T05","5567.587","-2755.973","0",""
"R181","10K_5%_0402","BottomLayer","RESC1005X40X25ML05T05","5421.260","-2799.213","90",""
"R180","10K_5%_0402","BottomLayer","RESC1005X40X25ML05T05","5669.949","-2728.414","0",""
"R49","10K_5%_0402","BottomLayer","RESC1005X40X25ML05T05","5342.349","-2824.808","180",""
"C115","0.1uF_25V_0402","BottomLayer","FP-0402-L_1_0_1-W_0_5_0_1-IPC_C","5962.203","-2782.794","90","General Purpose Ceramic Capacitor, 0402, 100nF, 10%, X7R, 15%, 25V"
"C114","1uF_16V_0402","BottomLayer","FP-0402-L_1_0_0_05-W_0_5-IPC_A","5962.203","-2857.597","270","None"
"C113","0.1uF_25V_0402","BottomLayer","FP-0402-L_1_0_1-W_0_5_0_1-IPC_C","5569.359","-2807.548","180","General Purpose Ceramic Capacitor, 0402, 100nF, 10%, X7R, 15%, 25V"
"C112","0.1uF_25V_0402","BottomLayer","FP-0402-L_1_0_1-W_0_5_0_1-IPC_C","5808.659","-2774.919","90","General Purpose Ceramic Capacitor, 0402, 100nF, 10%, X7R, 15%, 25V"
"C111","1uF_16V_0402","BottomLayer","FP-0402-L_1_0_0_05-W_0_5-IPC_A","5808.659","-2853.660","270","None"
"C110","0.1uF_25V_0402","BottomLayer","FP-0402-L_1_0_1-W_0_5_0_1-IPC_C","5444.711","-2718.509","90","General Purpose Ceramic Capacitor, 0402, 100nF, 10%, X7R, 15%, 25V"
"R179","200_1%_0402","TopLayer","RESC1005X40X25NL05T05","5972.441","-1444.882","180",""
"R178","200_1%_0402","BottomLayer","RESC1005X40X25NL05T05","5889.764","-1858.268","180",""
"R141","10K_1%_0402","BottomLayer","RESC1005X40X25LL05T10","5897.304","-1602.213","270",""
"R140","10K_1%_0402","BottomLayer","RESC1005X40X25LL05T10","5897.638","-1771.653","90",""
"D19","LTST-C191KGKT","TopLayer","FP-LTST-C191KGKT-MFG","5976.378","-1500.000","0","LED GREEN CLEAR SMD"
"D12","LTST-C191KGKT","TopLayer","FP-LTST-C191KGKT-MFG","6029.528","-1861.073","0","LED GREEN CLEAR SMD"
"U29","PI3A412ZHE","TopLayer","ZH16_PER","1507.874","3.937","0","No Description Available"
"U28","PI3A412ZHE","TopLayer","ZH16_PER","4783.465","-3039.370","0","No Description Available"
"U31","TMUX1072RUTR","TopLayer","FP-RUT0012A-MFG","1897.638","-944.882","90","IC SWITCH SPDT DUAL 12UQFN"
"U30","TMUX1072RUTR","TopLayer","FP-RUT0012A-MFG","4803.150","-2657.480","0","IC SWITCH SPDT DUAL 12UQFN"
"R177","49.9_1%_0402","TopLayer","RESC1005X40X25LL05T10","2000.000","-917.323","0",""
"R176","49.9_1%_0402","TopLayer","RESC1005X40X25LL05T10","1791.339","-921.260","180",""
"R175","49.9_1%_0402","TopLayer","RESC1005X40X25LL05T10","4826.772","-2779.528","270",""
"R174","DNI_49.9_1%_0402","TopLayer","RESC1005X40X25LL05T10","1988.189","-1027.559","180",""
"R173","DNI_49.9_1%_0402","TopLayer","RESC1005X40X25LL05T10","2000.000","-877.953","180",""
"R172","DNI_49.9_1%_0402","TopLayer","RESC1005X40X25LL05T10","1795.276","-1011.811","0",""
"R171","49.9_1%_0402","TopLayer","RESC1005X40X25LL05T10","4830.709","-2555.118","90",""
"R170","DNI_49.9_1%_0402","TopLayer","RESC1005X40X25LL05T10","1791.339","-877.953","0",""
"R169","DNI_49.9_1%_0402","TopLayer","RESC1005X40X25LL05T10","4799.213","-2779.528","90",""
"R168","DNI_49.9_1%_0402","TopLayer","RESC1005X40X25LL05T10","4858.268","-2779.528","90",""
"R167","DNI_49.9_1%_0402","TopLayer","RESC1005X40X25LL05T10","4767.717","-2555.118","270",""
"R166","DNI_49.9_1%_0402","TopLayer","RESC1005X40X25LL05T10","4874.016","-2555.118","270",""
"R165","DNI_27_1%_0402","TopLayer","RESC1005X40X25NL05T05","1692.913","114.173","90",""
"R164","DNI_27_1%_0402","TopLayer","RESC1005X40X25NL05T05","1535.433","-122.047","270",""
"R163","DNI_27_1%_0402","TopLayer","RESC1005X40X25NL05T05","1358.268","-62.992","180",""
"R162","DNI_27_1%_0402","TopLayer","RESC1005X40X25NL05T05","1511.811","161.417","90",""
"R161","DNI_27_1%_0402","TopLayer","RESC1005X40X25NL05T05","1598.425","114.173","90",""
"R160","DNI_27_1%_0402","TopLayer","RESC1005X40X25NL05T05","4940.945","-3035.433","0",""
"R159","DNI_27_1%_0402","TopLayer","RESC1005X40X25NL05T05","1625.984","-114.173","270",""
"R158","DNI_27_1%_0402","TopLayer","RESC1005X40X25NL05T05","4866.142","-3177.165","0",""
"R157","DNI_27_1%_0402","TopLayer","RESC1005X40X25NL05T05","1429.134","-118.110","180",""
"R156","DNI_27_1%_0402","TopLayer","RESC1005X40X25NL05T05","4614.173","-3102.362","270",""
"R155","DNI_27_1%_0402","TopLayer","RESC1005X40X25NL05T05","1425.197","149.606","90",""
"R154","DNI_27_1%_0402","TopLayer","RESC1005X40X25NL05T05","4767.717","-2901.575","90",""
"R153","DNI_27_1%_0402","TopLayer","RESC1005X40X25NL05T05","4834.646","-2897.638","90",""
"R152","49.9_1%_0402","TopLayer","RESC1005X40X25LL05T10","1354.331","-98.425","180",""
"R151","DNI_27_1%_0402","TopLayer","RESC1005X40X25NL05T05","4913.386","-3102.362","0",""
"R150","49.9_1%_0402","TopLayer","RESC1005X40X25LL05T10","1586.614","-114.173","270",""
"R149","DNI_27_1%_0402","TopLayer","RESC1005X40X25NL05T05","4720.472","-3153.543","180",""
"R148","DNI_27_1%_0402","TopLayer","RESC1005X40X25NL05T05","4661.417","-2964.567","90",""
"R147","49.9_1%_0402","TopLayer","RESC1005X40X25LL05T10","1645.669","114.173","90",""
"R146","49.9_1%_0402","TopLayer","RESC1005X40X25LL05T10","4657.480","-3102.362","270",""
"R145","49.9_1%_0402","TopLayer","RESC1005X40X25LL05T10","4913.386","-3141.732","0",""
"R144","49.9_1%_0402","TopLayer","RESC1005X40X25LL05T10","1468.504","157.480","90",""
"R143","49.9_1%_0402","TopLayer","RESC1005X40X25LL05T10","4885.827","-2937.008","90",""
"R142","49.9_1%_0402","TopLayer","RESC1005X40X25LL05T10","4728.346","-2905.512","90",""
"C109","0.1uF_25V_0402","BottomLayer","FP-0402-L_1_0_1-W_0_5_0_1-IPC_C","1517.505","39.437","270","General Purpose Ceramic Capacitor, 0402, 100nF, 10%, X7R, 15%, 25V"
"C108","0.1uF_25V_0402","BottomLayer","FP-0402-L_1_0_1-W_0_5_0_1-IPC_C","4778.724","-3003.870","270","General Purpose Ceramic Capacitor, 0402, 100nF, 10%, X7R, 15%, 25V"
"C107","0.1uF_25V_0402","BottomLayer","FP-0402-L_1_0_1-W_0_5_0_1-IPC_C","1897.638","-944.882","270","General Purpose Ceramic Capacitor, 0402, 100nF, 10%, X7R, 15%, 25V"
"C106","0.1uF_25V_0402","BottomLayer","FP-0402-L_1_0_1-W_0_5_0_1-IPC_C","4803.150","-2657.480","180","General Purpose Ceramic Capacitor, 0402, 100nF, 10%, X7R, 15%, 25V"
"C105","0.1uF_25V_0402","BottomLayer","FP-0402-L_1_0_1-W_0_5_0_1-IPC_C","5733.268","-2611.220","0","General Purpose Ceramic Capacitor, 0402, 100nF, 10%, X7R, 15%, 25V"
"C104","0.1uF_25V_0402","BottomLayer","FP-0402-L_1_0_1-W_0_5_0_1-IPC_C","5659.449","-2611.193","180","General Purpose Ceramic Capacitor, 0402, 100nF, 10%, X7R, 15%, 25V"
"C103","0.1uF_25V_0402","BottomLayer","FP-0402-L_1_0_1-W_0_5_0_1-IPC_C","4976.378","-2598.425","180","General Purpose Ceramic Capacitor, 0402, 100nF, 10%, X7R, 15%, 25V"
"C102","0.1uF_25V_0402","BottomLayer","FP-0402-L_1_0_1-W_0_5_0_1-IPC_C","5076.772","-2601.362","0","General Purpose Ceramic Capacitor, 0402, 100nF, 10%, X7R, 15%, 25V"
"C101","0.1uF_25V_0402","BottomLayer","FP-0402-L_1_0_1-W_0_5_0_1-IPC_C","4972.441","-2523.622","180","General Purpose Ceramic Capacitor, 0402, 100nF, 10%, X7R, 15%, 25V"
"C100","0.1uF_25V_0402","BottomLayer","FP-0402-L_1_0_1-W_0_5_0_1-IPC_C","2141.732","-748.032","270","General Purpose Ceramic Capacitor, 0402, 100nF, 10%, X7R, 15%, 25V"
"C99","0.1uF_25V_0402","BottomLayer","FP-0402-L_1_0_1-W_0_5_0_1-IPC_C","2045.373","-750.000","270","General Purpose Ceramic Capacitor, 0402, 100nF, 10%, X7R, 15%, 25V"
"C98","0.1uF_25V_0402","BottomLayer","FP-0402-L_1_0_1-W_0_5_0_1-IPC_C","2141.732","-31.496","90","General Purpose Ceramic Capacitor, 0402, 100nF, 10%, X7R, 15%, 25V"
"C97","0.1uF_25V_0402","BottomLayer","FP-0402-L_1_0_1-W_0_5_0_1-IPC_C","2038.386","-29.528","90","General Purpose Ceramic Capacitor, 0402, 100nF, 10%, X7R, 15%, 25V"
"C74","0.1uF_25V_0402","BottomLayer","FP-0402-L_1_0_1-W_0_5_0_1-IPC_C","2094.488","27.559","90","General Purpose Ceramic Capacitor, 0402, 100nF, 10%, X7R, 15%, 25V"
"R139","0_1%_0402","TopLayer","RESC1005X40X25LL05T05","5503.937","-3007.874","180","Chip Resistor, 0 Ohm, 0.1 W, -55 to 155 degC, 0402 (1005 Metric), RoHS, Tape and Reel"
"R138","0_1%_0402","TopLayer","RESC1005X40X25LL05T05","1618.110","-590.551","180","Chip Resistor, 0 Ohm, 0.1 W, -55 to 155 degC, 0402 (1005 Metric), RoHS, Tape and Reel"
"R137","4.7K_1%_0402","BottomLayer","RESC1005X40X25NL10T10","5315.753","-2453.740","180",""
"R136","4.7K_1%_0402","BottomLayer","RESC1005X40X25NL10T10","5335.835","-2508.858","180",""
"R135","4.7K_1%_0402","BottomLayer","RESC1005X40X25NL10T10","5347.608","-2560.039","180",""
"R134","4.7K_1%_0402","BottomLayer","RESC1005X40X25NL10T10","2208.661","-342.990","90",""
"R133","4.7K_1%_0402","BottomLayer","RESC1005X40X25NL10T10","2153.543","-366.178","90",""
"R132","4.7K_1%_0402","BottomLayer","RESC1005X40X25NL10T10","2102.362","-387.581","90",""
"R131","DNI_0_1%_0402","TopLayer","RESC1005X40X25LL05T05","5433.071","-3007.874","0","Chip Resistor, 0 Ohm, 0.1 W, -55 to 155 degC, 0402 (1005 Metric), RoHS, Tape and Reel"
"R130","DNI_0_1%_0402","TopLayer","RESC1005X40X25LL05T05","1618.110","-543.307","180","Chip Resistor, 0 Ohm, 0.1 W, -55 to 155 degC, 0402 (1005 Metric), RoHS, Tape and Reel"
"J45","2199119-3","TopLayer","FP-2199119-3-MFG","5358.268","-2772.638","180","CONN M.2 FEMALE 67POS 0.020 GOLD"
"J44","2199119-3","TopLayer","FP-2199119-3-MFG","1889.764","-389.764","90","CONN M.2 FEMALE 67POS 0.020 GOLD"
"C73","47uF_35V_2917","TopLayer","FP-T521X476M035ATE030-MFG","4539.370","-1480.315","90","CAP TANT POLY 47UF 35V 2917"
"C72","47uF_35V_2917","TopLayer","FP-T521X476M035ATE030-MFG","972.441","122.047","180","CAP TANT POLY 47UF 35V 2917"
"C71","470uF_10V_2917","TopLayer","FP-TAJE-MFG","1035.433","-500.000","90","470uF 10V  ±10% 500mO 2917  SMD Tantalum Capacitor"
"R129","20K_1%_0402","BottomLayer","RESC1005X40X25NL10T10","4528.543","-1460.630","270",""
"CR1","MBRD10200CT-13","TopLayer","TO252(DPAK)_DIO","5590.730","-366.142","270","No Description Available"
"J43","47589-0001","TopLayer","MOLX-47589-0001_V","6141.732","-2800.197","90","Right Angle Female Type AB Micro USB Connector, 30 V, 1.8 A, -30 to 85 degC, RoHS, Tape and Reel"
"R69","0_1%_0402","BottomLayer","RESC1005X40X25LL05T05","4236.220","-1055.118","180","Chip Resistor, 0 Ohm, 0.1 W, -55 to 155 degC, 0402 (1005 Metric), RoHS, Tape and Reel"
"U24","MUN12AD06-SM","TopLayer","MUN12AD06-SM_CYN","4220.472","-1160.434","180","No Description Available"
"U1","MUN12AD06-SM","TopLayer","MUN12AD06-SM_CYN","1005.575","-137.795","270","No Description Available"
"Y1","ABS07-32.768KHZ-T","TopLayer","FP-ABS07-MFG","1825.162","-1234.252","90","Crystal 32.768kHz ±20ppm (Tol) 12.5pF FUND 70k? 2-Pin CSMD T/R"
"U27","PCA9546ARGVR","TopLayer","RGV0016A_V","3866.142","-2342.520","90","4-Channel I2C and SMBus Multiplexer with Reset Functions, 2.3 to 5.5 V, -40 to 85 degC, 16-pin VQFN (RGV), Green (RoHS & no Sb/Br)"
"U26","TMUX1072RUTR","TopLayer","FP-RUT0012A-MFG","3255.905","-2397.638","0","IC SWITCH SPDT DUAL 12UQFN"
"U25","NCP176AMX330TCG","TopLayer","FP-711AT-MFG","1614.173","-1015.647","0","IC REG LINEAR 3.3V 500MA 6XDFN"
"SW2","219-2LPST","TopLayer","CTS-219-2LPST_V","6074.803","-1688.976","180","Surface Mount DIP Switch Auto Placeable, -55 to 85 degC, 4-Pin SMD, RoHS, Tube"
"R128","27_1%_0402","TopLayer","RESC1005X40X25NL05T05","3724.409","-2366.142","0",""
"R127","27_1%_0402","TopLayer","RESC1005X40X25NL05T05","3724.409","-2413.386","0",""
"R126","27_1%_0402","TopLayer","RESC1005X40X25NL05T05","3948.819","-2192.913","180",""
"R125","200_1%_0402","BottomLayer","RESC1005X40X25NL05T05","5901.575","-2260.827","270",""
"R124","4.7K_1%_0402","TopLayer","RESC1005X40X25NL10T10","3846.457","-2177.165","0",""
"R123","4.7K_1%_0402","TopLayer","RESC1005X40X25NL10T10","3732.284","-2177.165","180",""
"R122","200_1%_0402","BottomLayer","RESC1005X40X25NL05T05","5846.457","-2307.087","270",""
"R121","27_1%_0402","TopLayer","RESC1005X40X25NL05T05","3826.772","-2480.315","90",""
"R120","4.7K_1%_0402","TopLayer","RESC1005X40X25NL10T10","3909.449","-2507.874","270",""
"R119","4.7K_1%_0402","TopLayer","RESC1005X40X25NL10T10","3866.142","-2507.874","270",""
"R118","4.7K_1%_0402","TopLayer","RESC1005X40X25NL10T10","4015.748","-2507.874","270",""
"R117","4.7K_1%_0402","TopLayer","RESC1005X40X25NL10T10","3968.504","-2507.874","270",""
"R116","4.7K_1%_0402","TopLayer","RESC1005X40X25NL10T10","4074.803","-2330.709","0",""
"R115","4.7K_1%_0402","TopLayer","RESC1005X40X25NL10T10","4070.866","-2381.890","0",""
"R114","4.7K_1%_0402","TopLayer","RESC1005X40X25NL10T10","4062.992","-2196.850","0",""
"R113","4.7K_1%_0402","TopLayer","RESC1005X40X25NL10T10","4062.992","-2240.157","0",""
"R112","200_1%_0402","BottomLayer","RESC1005X40X25NL05T05","5818.898","-2418.307","270",""
"R111","27_1%_0402","TopLayer","RESC1005X40X25NL05T05","3141.732","-2433.071","0",""
"P5","61300411121","TopLayer","61300411121","3212.598","-1406.693","90","THT Vertical Pin Header WR-PHD, Pitch 2.54 mm, Single Row, 4 pins"
"P4","TSM-105-01-L-DV","TopLayer","SMTC-TSM-105-01-X-DV","6123.031","-3333.071","90","0.025" SQ Post Header, Surface Mount, Vertical, -55 to 125 degC, 2.54 mm Pitch, 10-Pin, Male, RoHS"
"C39","22pF_50V_0402","TopLayer","CAPC1005X55X25ML05T05","1892.091","-1194.882","270","Chip Capacitor, 22 pF, +/- 5%, 50 V, -55 to 125 degC, 0402 (1005 Metric), RoHS, Tape and Reel"
"R110","DNI_4.7K_0402","TopLayer","RESC1005X40X25LL05T05","493.514","-1155.414","180","Chip Resistor, 4.7 KOhm, +/- 1%, 0.1 W, -55 to 155 degC, 0402 (1005 Metric), RoHS, Tape and Reel"
"R109","4.7K_0402","TopLayer","RESC1005X40X25LL05T05","493.514","-1080.611","0","Chip Resistor, 4.7 KOhm, +/- 1%, 0.1 W, -55 to 155 degC, 0402 (1005 Metric), RoHS, Tape and Reel"
"R108","4.7K_0402","TopLayer","RESC1005X40X25LL05T05","493.514","-1116.044","0","Chip Resistor, 4.7 KOhm, +/- 1%, 0.1 W, -55 to 155 degC, 0402 (1005 Metric), RoHS, Tape and Reel"
"R107","DNI_49.9_1%_0402","TopLayer","RESC1005X40X25LL05T10","2913.386","-1897.638","0",""
"R106","DNI_49.9_1%_0402","TopLayer","RESC1005X40X25LL05T10","2933.071","-1940.945","0",""
"R105","DNI_49.9_1%_0402","TopLayer","RESC1005X40X25LL05T10","2712.598","-1964.567","180",""
"R104","DNI_49.9_1%_0402","TopLayer","RESC1005X40X25LL05T10","2712.598","-1921.260","180",""
"R103","DNI_27_1%_0402","TopLayer","RESC1005X40X25NL05T05","3196.850","-3035.433","0",""
"R102","DNI_27_1%_0402","TopLayer","RESC1005X40X25NL05T05","3200.787","-2834.646","0",""
"R101","DNI_27_1%_0402","TopLayer","RESC1005X40X25NL05T05","3397.638","-3031.496","0",""
"R100","DNI_27_1%_0402","TopLayer","RESC1005X40X25NL05T05","3393.701","-2811.024","0",""
"U23","TMUX1072RUTR","TopLayer","FP-RUT0012A-MFG","2818.898","-1952.756","90","IC SWITCH SPDT DUAL 12UQFN"
"U22","TMUX1072RUTR","TopLayer","FP-RUT0012A-MFG","3204.724","-2937.008","0","IC SWITCH SPDT DUAL 12UQFN"
"U21","TMUX1072RUTR","TopLayer","FP-RUT0012A-MFG","3393.701","-2929.134","0","IC SWITCH SPDT DUAL 12UQFN"
"U20","FT234XD-R","TopLayer","FP-DFN-12-IPC_B","6152.559","-2410.059","90","IC USB SERIAL BASIC UART 12DFN"
"SW1","1571983-4","TopLayer","FP-1571983-4-MFG","6099.773","-2038.533","90","SWITCH SLIDE DIP SPST 25MA 24V"
"R99","49.9_1%_0402","TopLayer","RESC1005X40X25LL05T10","2838.583","-2057.086","90",""
"R98","49.9_1%_0402","TopLayer","RESC1005X40X25LL05T10","2858.268","-1854.331","270",""
"R97","49.9_1%_0402","TopLayer","RESC1005X40X25LL05T10","2795.276","-2059.055","90",""
"R96","49.9_1%_0402","TopLayer","RESC1005X40X25LL05T10","2783.465","-1854.331","270",""
"R95","27_1%_0402","TopLayer","RESC1005X40X25NL05T05","3366.142","-2429.134","180",""
"R94","27_1%_0402","TopLayer","RESC1005X40X25NL05T05","3169.291","-2362.205","0",""
"R93","27_1%_0402","TopLayer","RESC1005X40X25NL05T05","3090.551","-2964.567","0",""
"R92","27_1%_0402","TopLayer","RESC1005X40X25NL05T05","3287.402","-3005.905","90",""
"R91","27_1%_0402","TopLayer","RESC1005X40X25NL05T05","3098.425","-2893.701","0",""
"R90","27_1%_0402","TopLayer","RESC1005X40X25NL05T05","3279.528","-2842.520","270",""
"R89","10K_1%_0402","BottomLayer","RESC1005X40X25LL05T10","5854.331","-1968.504","0",""
"R88","10K_1%_0402","BottomLayer","RESC1005X40X25LL05T10","5838.583","-2066.929","0",""
"R87","27_1%_0402","TopLayer","RESC1005X40X25NL05T05","3330.709","-3007.874","90",""
"R86","27_1%_0402","TopLayer","RESC1005X40X25NL05T05","3498.032","-2960.630","180",""
"R85","27_1%_0402","TopLayer","RESC1005X40X25NL05T05","3330.709","-2842.520","270",""
"R84","27_1%_0402","TopLayer","RESC1005X40X25NL05T05","3505.905","-2885.827","180",""
"R83","15K_1%_0402","TopLayer","FP-ERJ2R-MFG","6106.299","-2566.929","0","RES SMD 15K OHM 1% 1/10W 0402"
"R82","10K_1%_0402","TopLayer","RESC1005X40X25LL05T10","6110.236","-2527.559","180",""
"R81","27_1%_0402","TopLayer","RESC1005X40X25NL05T05","6024.606","-2389.764","0",""
"FB1","600ohm_1.3A_0603","TopLayer","FP-BLM18-0_15-t0_8-IPC_A","6023.622","-3000.000","0","Chip Ferrite Bead, 0603, 600O @ 100MHz, 0.15O, 25%, 1.3A"
"D24","LTST-C191KGKT","TopLayer","FP-LTST-C191KGKT-MFG","6007.874","-2204.724","0","LED GREEN CLEAR SMD"
"C96","0.1uF_25V_0402","BottomLayer","FP-0402-L_1_0_1-W_0_5_0_1-IPC_C","2818.898","-1952.756","270","General Purpose Ceramic Capacitor, 0402, 100nF, 10%, X7R, 15%, 25V"
"C95","0.1uF_25V_0402","BottomLayer","FP-0402-L_1_0_1-W_0_5_0_1-IPC_C","3204.724","-2937.008","180","General Purpose Ceramic Capacitor, 0402, 100nF, 10%, X7R, 15%, 25V"
"C94","0.1uF_25V_0402","BottomLayer","FP-0402-L_1_0_1-W_0_5_0_1-IPC_C","3393.701","-2929.134","180","General Purpose Ceramic Capacitor, 0402, 100nF, 10%, X7R, 15%, 25V"
"C93","0.1uF_25V_0402","BottomLayer","FP-0402-L_1_0_1-W_0_5_0_1-IPC_C","6129.921","-2385.827","0","General Purpose Ceramic Capacitor, 0402, 100nF, 10%, X7R, 15%, 25V"
"C92","0.1uF_25V_0402","BottomLayer","FP-0402-L_1_0_1-W_0_5_0_1-IPC_C","6143.258","-2311.024","0","General Purpose Ceramic Capacitor, 0402, 100nF, 10%, X7R, 15%, 25V"
"C91","10nF_50V_0402","TopLayer","FP-CC0402-MFG","6106.299","-2610.236","180","CAP CER 10000PF 50V X7R 0402"
"C90","4.7uF_16V_0402","BottomLayer","FP-CL829-IPC_C","6142.716","-3027.559","0","Cap Ceramic 4.7uF 16V X5R ±20% SMD 0402 +85°C Paper T/R"
"C89","0.1uF_25V_0402","TopLayer","FP-0402-L_1_0_1-W_0_5_0_1-IPC_C","6145.669","-3027.559","0","General Purpose Ceramic Capacitor, 0402, 100nF, 10%, X7R, 15%, 25V"
"C88","47pF_50V_0402","BottomLayer","CAPC1005X55X25LL05T10","6027.165","-2429.914","180",""
"C87","47pF_50V_0402","BottomLayer","CAPC1005X55X25LL05T10","6027.165","-2390.544","180",""
"C86","10nF_50V_0402","TopLayer","FP-CC0402-MFG","5980.315","-2921.260","180","CAP CER 10000PF 50V X7R 0402"
"D23","SMDJ12A","TopLayer","FP-DO-214AB_SMC_J-Bend-MFG","5637.795","-645.669","180","TVS DIODE 12V 19.9V DO214AB"
"R77","200_1%_0402","TopLayer","FP-ERJ2RK-IPC_A","4696.850","-763.779","180","RES SMD 200 OHM 1% 1/10W 0402"
"D20","LTST-C191KGKT","TopLayer","FP-LTST-C191KGKT-MFG","4545.276","-763.780","0","LED GREEN CLEAR SMD"
"D22","LTST-C191KGKT","TopLayer","FP-LTST-C191KGKT-MFG","6007.874","-2267.716","0","LED GREEN CLEAR SMD"
"D21","LTST-C191KGKT","TopLayer","FP-LTST-C191KGKT-MFG","6007.874","-2330.709","0","LED GREEN CLEAR SMD"
"U19","INA219BIDR","TopLayer","FP-D0008A-MFG","3805.826","-1448.819","90","IC MONITOR PWR/CURR BIDIR 8-SOIC"
"U18","DNI_MYMGK00506ERSR","TopLayer","FP-MYMGK-12-MFG","4228.346","-1488.189","270","DC DC CONVERTER 0.7-5V"
"U17","INA219BIDR","TopLayer","FP-D0008A-MFG","554.725","-508.554","0","IC MONITOR PWR/CURR BIDIR 8-SOIC"
"R80","0_1%_0402","BottomLayer","RESC1005X40X25LL05T05","3730.826","-1555.118","90","Chip Resistor, 0 Ohm, 0.1 W, -55 to 155 degC, 0402 (1005 Metric), RoHS, Tape and Reel"
"R79","0_1%_0402","BottomLayer","RESC1005X40X25LL05T05","3780.826","-1555.118","90","Chip Resistor, 0 Ohm, 0.1 W, -55 to 155 degC, 0402 (1005 Metric), RoHS, Tape and Reel"
"R78","10K_1%_0402","BottomLayer","RESC1005X40X25LL05T10","5838.583","-2141.732","0",""
"R76","27_1%_0402","TopLayer","RESC1005X40X25NL05T05","3362.205","-2358.268","180",""
"R75","DNI_27_1%_0402","TopLayer","RESC1005X40X25NL05T05","3224.409","-2507.874","0",""
"R74","DNI_27_1%_0402","TopLayer","RESC1005X40X25NL05T05","3224.409","-2287.402","0",""
"R73","DNI_0_1%_0402","TopLayer","RESC1005X40X25LL05T05","1829.099","-1328.740","0","Chip Resistor, 0 Ohm, 0.1 W, -55 to 155 degC, 0402 (1005 Metric), RoHS, Tape and Reel"
"R72","2mOhm_1%_1206","TopLayer","RESC3216X89X64NL25T25","3941.929","-1208.661","180",""
"R71","DNI_0_1%_0402","TopLayer","RESC1005X40X25LL05T05","1829.099","-1135.827","0","Chip Resistor, 0 Ohm, 0.1 W, -55 to 155 degC, 0402 (1005 Metric), RoHS, Tape and Reel"
"R70","4.7K_1%_0402","BottomLayer","RESC1005X40X25NL10T10","4163.980","-1046.434","180",""
"R68","2K_0.5%_0402","BottomLayer","RESC1005X35X25LL10T10","4024.606","-1299.213","180",""
"R67","88.7K_0.5%_0402","BottomLayer","FP-RT0402-MFG","4102.362","-1295.276","180","RES SMD 88.7K OHM 0.5% 1/16W"
"R66","0_1%_0402","BottomLayer","RESC1005X40X25LL05T05","448.425","-433.554","0","Chip Resistor, 0 Ohm, 0.1 W, -55 to 155 degC, 0402 (1005 Metric), RoHS, Tape and Reel"
"R65","0_1%_0402","BottomLayer","RESC1005X40X25LL05T05","448.425","-483.554","0","Chip Resistor, 0 Ohm, 0.1 W, -55 to 155 degC, 0402 (1005 Metric), RoHS, Tape and Reel"
"R64","0_1%_0402","BottomLayer","RESC1005X40X25LL05T05","5984.252","-814.961","90","Chip Resistor, 0 Ohm, 0.1 W, -55 to 155 degC, 0402 (1005 Metric), RoHS, Tape and Reel"
"R63","22_0.5%_0402","BottomLayer","FP-RG1005-IPC_A","4299.213","-1326.772","180","Automotive Metal Thin Film Chip Resistor, 0402, 22O, 0.5%, 100ppm/°C, 0.0625W, 75V"
"R62","0_1%_0402","BottomLayer","RESC1005X40X25LL05T05","6033.565","-814.331","90","Chip Resistor, 0 Ohm, 0.1 W, -55 to 155 degC, 0402 (1005 Metric), RoHS, Tape and Reel"
"R61","2.2K_0.5%_0402","BottomLayer","RESC1005X40X25ML10T10","4257.874","-1379.921","180",""
"R60","10K_1%_0402","BottomLayer","RESC1005X40X25NL10T10","511.811","3.937","0",""
"R59","10K_1%_0402","BottomLayer","RESC1005X40X25NL10T10","700.787","7.874","180",""
"C85","10uF_16V_0603","BottomLayer","FP-0603-L_1_6_0_2-W_0_8_0-MFG","3859.566","-1350.394","180","Multilayer Ceramic Capacitor 10uF 16V X5R 20% SMD 0603 T/R"
"C84","0.1uF_25V_0402","BottomLayer","CAPC1005X56X25NL10T15","1729.392","-1225.441","90",""
"C83","0.1uF_25V_0402","TopLayer","FP-0402-L_1_0_1-W_0_5_0_1-IPC_C","3906.538","-1119.899","90","General Purpose Ceramic Capacitor, 0402, 100nF, 10%, X7R, 15%, 25V"
"C82","1uF_16V_0402","TopLayer","FP-0402-L_1_0_0_05-W_0_5-IPC_A","3548.664","-1198.819","180","None"
"C81","2.2uF_16V_0402","TopLayer","FP-C1005-050-0_05-IPC_A","3548.664","-1131.890","180","Multilayer Ceramic Capacitors 2.2µF ±10% 16V X5R SMD 0402"
"C80","10uF_16V_0603","TopLayer","FP-0603-L_1_6_0_2-W_0_8_0-MFG","3832.677","-1118.110","90","Multilayer Ceramic Capacitor 10uF 16V X5R 20% SMD 0603 T/R"
"C79","100uF_16V_2917","TopLayer","FP-T495D107K016ATE125-MFG","3464.173","-1338.583","0","CAP TANT 100UF 10% 16V 2917"
"C78","47uF_16V_1206","TopLayer","FP-C3216-160-0_2-MFG","3688.976","-1118.110","180","Multilayer Ceramic Capacitors 47uF ±20% 16V X5R SMD 1206"
"C77","4.7uF_50V_1206","TopLayer","FP-GRM31C-0_2-e0_3_0_8-IPC_C","4599.379","-1251.968","0","Chip Multilayer Ceramic Capacitors for General Purpose, 1206, 4.7uF, X7R, 15%, 10%, 50V"
"C76","4.7uF_50V_1206","TopLayer","FP-GRM31C-0_2-e0_3_0_8-IPC_C","4433.071","-1173.228","90","Chip Multilayer Ceramic Capacitors for General Purpose, 1206, 4.7uF, X7R, 15%, 10%, 50V"
"C75","100uF_16V_2917","TopLayer","FP-T495D107K016ATE125-MFG","4574.803","-1019.685","270","CAP TANT 100UF 10% 16V 2917"
"C70","0.1uF_25V_0402","BottomLayer","FP-0402-L_1_0_1-W_0_5_0_1-IPC_C","3779.528","-2329.724","0","General Purpose Ceramic Capacitor, 0402, 100nF, 10%, X7R, 15%, 25V"
"C69","0.1uF_25V_0402","BottomLayer","FP-0402-L_1_0_1-W_0_5_0_1-IPC_C","3255.905","-2397.638","180","General Purpose Ceramic Capacitor, 0402, 100nF, 10%, X7R, 15%, 25V"
"C68","22pF_50V_0402","TopLayer","CAPC1005X55X25ML05T05","1892.091","-1293.307","90","Chip Capacitor, 22 pF, +/- 5%, 50 V, -55 to 125 degC, 0402 (1005 Metric), RoHS, Tape and Reel"
"R58","4.7K_0402","BottomLayer","RESC1005X40X25LL05T05","1592.879","-1214.567","180","Chip Resistor, 4.7 KOhm, +/- 1%, 0.1 W, -55 to 155 degC, 0402 (1005 Metric), RoHS, Tape and Reel"
"R57","4.7K_0402","BottomLayer","RESC1005X40X25LL05T05","1580.084","-1170.276","270","Chip Resistor, 4.7 KOhm, +/- 1%, 0.1 W, -55 to 155 degC, 0402 (1005 Metric), RoHS, Tape and Reel"
"R56","DNI_4.7K_0402","BottomLayer","RESC1005X40X25LL05T05","1565.320","-1372.047","0","Chip Resistor, 4.7 KOhm, +/- 1%, 0.1 W, -55 to 155 degC, 0402 (1005 Metric), RoHS, Tape and Reel"
"R55","4.7K_0402","BottomLayer","RESC1005X40X25LL05T05","1592.879","-1250.000","0","Chip Resistor, 4.7 KOhm, +/- 1%, 0.1 W, -55 to 155 degC, 0402 (1005 Metric), RoHS, Tape and Reel"
"R54","0_1%_0402","BottomLayer","RESC1005X40X25LL05T05","1588.942","-1289.370","180","Chip Resistor, 0 Ohm, 0.1 W, -55 to 155 degC, 0402 (1005 Metric), RoHS, Tape and Reel"
"R53","4.7K_0402","BottomLayer","RESC1005X40X25LL05T05","1640.123","-1364.173","0","Chip Resistor, 4.7 KOhm, +/- 1%, 0.1 W, -55 to 155 degC, 0402 (1005 Metric), RoHS, Tape and Reel"
"R52","4.7K_0402","BottomLayer","RESC1005X40X25LL05T05","1640.123","-1297.244","270","Chip Resistor, 4.7 KOhm, +/- 1%, 0.1 W, -55 to 155 degC, 0402 (1005 Metric), RoHS, Tape and Reel"
"R51","4.7K_0402","BottomLayer","RESC1005X40X25LL05T05","1631.711","-1175.966","180","Chip Resistor, 4.7 KOhm, +/- 1%, 0.1 W, -55 to 155 degC, 0402 (1005 Metric), RoHS, Tape and Reel"
"R50","4.7K_0402","BottomLayer","RESC1005X40X25LL05T05","1580.084","-1321.851","180","Chip Resistor, 4.7 KOhm, +/- 1%, 0.1 W, -55 to 155 degC, 0402 (1005 Metric), RoHS, Tape and Reel"
"C67","0.1uF_25V_0402","BottomLayer","CAPC1005X56X25NL10T15","1684.414","-1170.276","270",""
"C66","0.1uF_25V_0402","BottomLayer","CAPC1005X56X25NL10T15","3862.641","-1413.386","0",""
"C65","1uF_0402","BottomLayer","FP-0402-L_1_0_0_05-W_0_5-IPC_C","1514.139","-1242.126","180","None"
"C64","0.1uF","BottomLayer","CAPC1608X87X45ML20T05","5582.677","-3401.575","0","C0603X104K5RACAUTO"
"C57","0.1uF","BottomLayer","CAPC1608X87X45ML20T05","5661.417","-3192.913","180","C0603X104K5RACAUTO"
"C56","10uF","BottomLayer","FP-MK212BG-MFG","5570.866","-3303.150","180","None"
"C55","10uF","BottomLayer","FP-MK212BG-MFG","5661.417","-3098.425","0","None"
"C54","0.1uF","BottomLayer","CAPC1608X87X45ML20T05","1205.807","-474.013","0","C0603X104K5RACAUTO"
"C43","0.1uF","BottomLayer","CAPC1608X87X45ML20T05","1629.921","-456.693","90","C0603X104K5RACAUTO"
"C42","10uF","BottomLayer","FP-MK212BG-MFG","1254.036","-745.745","0","None"
"C41","10uF","BottomLayer","FP-MK212BG-MFG","1486.321","-457.181","270","None"
"R48","DNI_0_1%_0402","BottomLayer","RESC1005X40X25LL05T05","452.756","-1488.189","0","Chip Resistor, 0 Ohm, 0.1 W, -55 to 155 degC, 0402 (1005 Metric), RoHS, Tape and Reel"
"SKT10","0332-0-43-80-18-27-10-0","TopLayer","SolderSocket","1622.205","-3342.520","90","Solder socket for pin headers"
"SKT9","0332-0-43-80-18-27-10-0","TopLayer","SolderSocket","2181.102","-3236.220","90","Solder socket for pin headers"
"SKT8","0332-0-43-80-18-27-10-0","TopLayer","SolderSocket","1742.205","-3342.520","90","Solder socket for pin headers"
"SKT7","0332-0-43-80-18-27-10-0","TopLayer","SolderSocket","2181.102","-1637.795","90","Solder socket for pin headers"
"SKT6","0332-0-43-80-18-27-10-0","TopLayer","SolderSocket","582.677","-2437.008","90","Solder socket for pin headers"
"SKT5","0332-0-43-80-18-27-10-0","TopLayer","SolderSocket","582.677","-3236.220","90","Solder socket for pin headers"
"SKT4","0332-0-43-80-18-27-10-0","TopLayer","SolderSocket","2098.425","-3342.520","90","Solder socket for pin headers"
"SKT3","0332-0-43-80-18-27-10-0","TopLayer","SolderSocket","1980.315","-3342.520","90","Solder socket for pin headers"
"SKT2","0332-0-43-80-18-27-10-0","TopLayer","SolderSocket","582.677","-1637.795","90","Solder socket for pin headers"
"SKT1","0332-0-43-80-18-27-10-0","TopLayer","SolderSocket","1862.205","-3342.520","90","Solder socket for pin headers"
"P1","TSW-105-05-L-S","TopLayer","SMTC-TSW-105-05-X-S","2980.315","-1355.118","90","0.025" SQ Post Header, Through-hole, Vertical, -55 to 125 degC, 2.54 mm Pitch, 5-Pin, Male, RoHS"
"R47","DNI_0_5%_1206","TopLayer","RESC3116X65X50ML20T20","2702.756","-1525.591","0",""
"J38","39-30-0040","TopLayer","FP-39-30-0040-MFG","5779.095","-8.051","90","CONN HEADER R/A 4POS 4.2MM"
"R46","DNI_0_5%_1206","TopLayer","RESC3116X65X50ML20T20","2702.756","-1289.370","0",""
"R45","0_5%_1206","TopLayer","RESC3116X65X50ML20T20","2702.756","-1411.417","0",""
"R44","DNI_0_5%_1206","TopLayer","RESC3116X65X50ML20T20","5992.126","-342.520","270",""
"J37","Single FPGA Conn","TopLayer","SingleFPGAConn","3510.871","-3298.899","90",""
"J36","Single FPGA Conn","TopLayer","SingleFPGAConn","2610.818","-2553.373","0",""
"J35","Single FPGA Conn","TopLayer","SingleFPGAConn","3510.871","-1817.690","270",""
"J34","Single FPGA Conn","TopLayer","SingleFPGAConn","4485.728","-2553.373","180",""
"J31","SA53_Header","TopLayer","SA53_Header","2170.668","-2436.800","180",""
"J13","GNSS Header 16-pin","TopLayer","GNSS_Header_16-pin","5332.189","-3201.673","90",""
"J6","GNSS Header 16-pin","TopLayer","GNSS_Header_16-pin","1382.973","-457.181","0",""
"R43","27_1%_0402","TopLayer","RESC1005X40X25NL05T05","6024.606","-2429.134","0",""
"R42","27_1%_0402","TopLayer","RESC1005X40X25NL05T05","6122.047","-2287.402","180",""
"D10","LTST-C191KGKT","TopLayer","FP-LTST-C191KGKT-MFG","287.402","49.213","0","LED GREEN CLEAR SMD"
"D9","LTST-C191KGKT","TopLayer","FP-LTST-C191KGKT-MFG","287.402","118.110","0","LED GREEN CLEAR SMD"
"D3","LTST-C191KGKT","TopLayer","FP-LTST-C191KGKT-MFG","287.402","187.008","0","LED GREEN CLEAR SMD"
"U16","NC7WV125K8X","TopLayer","SOP50P310X90-8N","157.480","-3417.323","180","Integrated Circuit"
"U12","NC7WV125K8X","TopLayer","SOP50P310X90-8N","208.661","-2318.898","180","Integrated Circuit"
"U11","NC7WV125K8X","TopLayer","SOP50P310X90-8N","208.661","-2889.764","180","Integrated Circuit"
"U8","NC7WV125K8X","TopLayer","SOP50P310X90-8N","208.661","-1842.520","180","Integrated Circuit"
"U6","IS32FL3207","TopLayer","IS32FL3207","849.814","-1238.091","0",""
"R41","4.7K","TopLayer","RESC1608X55X30NL15T15","613.593","-1336.516","0","Precision Thick Film Chip Resistor, 4.7 KOhm, +/- 1%, -55 to 155 degC, 0603 (1608 Metric), RoHS, Tape and Reel ERJ-3EKF4701V"
"R40","DNI_100k","TopLayer","FP-RC0603-0_55-MFG","615.562","-1080.611","0","RES SMD 100K OHM 1% 1/10W 0603"
"R39","200 OHM","BottomLayer","RESC1608X55X30NL15T15","287.402","-43.307","180","ERJ-3EKF2000V"
"R38","200 OHM","BottomLayer","RESC1608X55X30NL15T15","287.402","25.590","180","ERJ-3EKF2000V"
"R36","200 OHM","BottomLayer","RESC1608X55X30NL15T15","287.402","94.488","180","ERJ-3EKF2000V"
"R35","200 OHM","BottomLayer","RESC1608X55X30NL15T15","287.402","163.386","180","ERJ-3EKF2000V"
"R34","49.9R","TopLayer","RESC1608X55X25NL10T15","11.811","-3381.890","90","General Purpose Chip Resistor, 49.9 Ohm, +/- 1%, -55 to 155 degC, 0603 (1608 Metric), RoHS, Tape and Reel"
"R33","49.9R","TopLayer","RESC1608X55X25NL10T15","114.173","-2232.284","90","General Purpose Chip Resistor, 49.9 Ohm, +/- 1%, -55 to 155 degC, 0603 (1608 Metric), RoHS, Tape and Reel"
"R32","4.7K_1%_0402","TopLayer","RESC1005X40X25NL10T10","-11.811","-3476.378","90",""
"R31","4.7K_1%_0402","TopLayer","RESC1005X40X25NL10T10","204.724","-3500.000","0",""
"P3","EXT GPIO","TopLayer","HDR2X6_CEN","6144.488","-1231.890","270","Header, 6-Pin, Dual row"
"J4","1909763-1","TopLayer","TECO-1909763-1_V","169.745","-3169.291","270","Ultra Miniature Coaxial Connector Jack, 60 V, 50 Ohm, -40 to 90 degC, RoHS, Tape and Reel"
"J2","1909763-1","TopLayer","TECO-1909763-1_V","169.745","-2106.299","270","Ultra Miniature Coaxial Connector Jack, 60 V, 50 Ohm, -40 to 90 degC, RoHS, Tape and Reel"
"J3","1909763-1","TopLayer","TECO-1909763-1_V","169.745","-2627.953","270","Ultra Miniature Coaxial Connector Jack, 60 V, 50 Ohm, -40 to 90 degC, RoHS, Tape and Reel"
"J1","1909763-1","TopLayer","TECO-1909763-1_V","169.745","-1573.323","270","Ultra Miniature Coaxial Connector Jack, 60 V, 50 Ohm, -40 to 90 degC, RoHS, Tape and Reel"
"D18","155124M173200","TopLayer","155124M173200","-190.453","-3413.386","90","LED (Multiple)"
"D17","155124M173200","TopLayer","155124M173200","-190.453","-2885.827","90","LED (Multiple)"
"D16","155124M173200","TopLayer","155124M173200","-190.453","-2350.394","90","LED (Multiple)"
"D15","155124M173200","TopLayer","155124M173200","-190.453","-1822.835","90","LED (Multiple)"
"C40","0.1uF","TopLayer","CAPC1608X87X45ML20T05","639.184","-1238.091","90","C0603X104K5RACAUTO"
"C38","1uF","TopLayer","FP-C0603C105K3PACTU-MFG","574.223","-1232.185","270","CAP CER 1UF 25V X5R 0603"
"C33","0.1uF_25V_0402","BottomLayer","FP-0402-L_1_0_1-W_0_5_0_1-IPC_C","1586.614","-999.899","90","General Purpose Ceramic Capacitor, 0402, 100nF, 10%, X7R, 15%, 25V"
"C32","1uF_16V_0402","TopLayer","FP-0402-L_1_0_0_05-W_0_5-IPC_A","1531.496","-1015.748","270","None"
"R37","10K","BottomLayer","RESC1608X55X30LL15T20","4322.372","-2019.685","90","Chip Resistor, 10 KOhm, +/- 1%, 0.1 W, -55 to 155 degC, 0603 (1608 Metric), RoHS, Tape and Reel RMCF0603FT10K0"
"U15","RCB-F9T-1","TopLayer","GNSS","5489.669","-3201.673","90","MOD, GPS"
"C37","0.1uF","BottomLayer","CAPC1608X87X45ML20T05","5330.709","-3389.764","180","C0603X104K5RACAUTO"
"C36","0.1uF","BottomLayer","CAPC1608X87X45ML20T05","5334.646","-3007.874","180","C0603X104K5RACAUTO"
"C35","10uF","BottomLayer","FP-MK212BG-MFG","5332.189","-3288.373","0","None"
"C34","10uF","BottomLayer","FP-MK212BG-MFG","5332.189","-3122.724","0","None"
"D2","8240136","TopLayer","SOT143-4L","-9.842","-2874.016","90","TVS Diode WE-TVS-HS, VRWM=3.3V"
"D1","8240136","TopLayer","SOT143-4L","-9.843","-1828.740","90","TVS Diode WE-TVS-HS, VRWM=3.3V"
"R27","160_0.5%_0402","BottomLayer","FP-RT0402-MFG","568.241","-335.630","90","RES SMD 160 OHM 0.5% 1/16W 0402"
"R26","1.2K_0.5%_0402","BottomLayer","RESC1005X40X25ML10T10","584.646","-273.622","0",""
"U10","MAC-SA5X","TopLayer","SA53","1416.043","-2470.157","180","MOD, MAC, MAC-SA5X, ATOMIC CLOCK"
"R14","4.7K_1%_0402","TopLayer","RESC1005X40X25NL10T10","248.031","-1925.197","0",""
"U14","BME280","TopLayer","FP-BME280-MFG","1318.193","-1283.499","270","SENSOR PRESSURE HUMIDITY TEMP"
"U13","BNO055","TopLayer","FP-BNO055-MFG","1632.249","-1265.748","0","IMU ACCEL/GYRO/MAG I2C 28LGA"
"U4","DS90LV028AQMA","TopLayer","M08A_L","2066.929","-1220.472","90","Automotive LVDS Dual Differential Line Receiver, 8-pin Narrow SOIC"
"U3","DS90LV027AQMA","TopLayer","M08A_N","2307.087","-1228.347","90","Automotive LVDS Dual Differential Driver, 8-pin Narrow SOIC"
"R25","49.9R","TopLayer","RESC1608X55X25NL10T15","129.921","-1755.906","180","General Purpose Chip Resistor, 49.9 Ohm, +/- 1%, -55 to 155 degC, 0603 (1608 Metric), RoHS, Tape and Reel"
"R17","4.7K_1%_0402","BottomLayer","RESC1005X40X25NL10T10","251.969","-2948.819","0",""
"R13","27_1%_0402","TopLayer","RESC1005X40X25NL05T05","6224.409","-2283.465","0",""
"R12","110R","BottomLayer","RESC1609X50X30NL10T20","2015.748","-1307.087","0",""
"R11","4.7K","BottomLayer","RESC1608X55X25LL10T15","2358.268","-1318.898","180","Chip Resistor, 4.7 KOhm, +/- 1%, 0.1 W, -55 to 155 degC, 0603 (1608 Metric), RoHS, Tape and Reel RC0603FR-074K7L"
"R10","4.7K","BottomLayer","RESC1608X55X25LL10T15","2255.905","-1326.772","0","Chip Resistor, 4.7 KOhm, +/- 1%, 0.1 W, -55 to 155 degC, 0603 (1608 Metric), RoHS, Tape and Reel RC0603FR-074K7L"
"C31","0.1uF","TopLayer","CAPC1608X87X45ML20T05","1312.150","-1104.624","0","C0603X104K5RACAUTO"
"C30","0.1uF","TopLayer","CAPC1608X87X45ML20T05","1312.785","-1161.468","0","C0603X104K5RACAUTO"
"C29","0.1uF_25V_0402","TopLayer","FP-0402-L_1_0_1-W_0_5_0_1-IPC_C","98.425","-2377.953","180","General Purpose Ceramic Capacitor, 0402, 100nF, 10%, X7R, 15%, 25V"
"C28","0.1uF_25V_0402","TopLayer","FP-0402-L_1_0_1-W_0_5_0_1-IPC_C","70.866","-3492.126","180","General Purpose Ceramic Capacitor, 0402, 100nF, 10%, X7R, 15%, 25V"
"C27","0.1uF_25V_0402","TopLayer","FP-0402-L_1_0_1-W_0_5_0_1-IPC_C","141.732","-2984.252","270","General Purpose Ceramic Capacitor, 0402, 100nF, 10%, X7R, 15%, 25V"
"C26","0.1uF_25V_0402","TopLayer","FP-0402-L_1_0_1-W_0_5_0_1-IPC_C","118.110","-1933.071","180","General Purpose Ceramic Capacitor, 0402, 100nF, 10%, X7R, 15%, 25V"
"C24","0.1uF","BottomLayer","CAPC1608X87X45ML20T05","1952.756","-1118.110","180","C0603X104K5RACAUTO"
"C23","0.1uF","BottomLayer","CAPC1608X87X45ML20T05","2200.787","-1381.890","0","C0603X104K5RACAUTO"
"AN1","RF2-49B-T-00-50-G-HDW","TopLayer","AMPH-901-143-6RFX_V","-84.645","-1573.323","180","Coaxial connector, 50 Ohm, -65 to 165 degC, 5-Pin THD, RoHS, Bulk"
"AN3","RF2-49B-T-00-50-G-HDW","TopLayer","AMPH-901-143-6RFX_V","-84.646","-2636.299","180","Coaxial connector, 50 Ohm, -65 to 165 degC, 5-Pin THD, RoHS, Bulk"
"AN2","RF2-49B-T-00-50-G-HDW","TopLayer","AMPH-901-143-6RFX_V","-84.646","-2104.803","180","Coaxial connector, 50 Ohm, -65 to 165 degC, 5-Pin THD, RoHS, Bulk"
"AN4","RF2-49B-T-00-50-G-HDW","TopLayer","AMPH-901-143-6RFX_V","-84.645","-3167.811","180","Coaxial connector, 50 Ohm, -65 to 165 degC, 5-Pin THD, RoHS, Bulk"
"U7","AT24MAC402-STUM-T","TopLayer","FP-5TS1-IPC_C","4283.002","-1968.504","270","IC EEPROM 2K I2C 1MHZ SOT23-5"
"C25","0.1uF","BottomLayer","CAPC1608X87X45ML20T05","4259.380","-1972.441","270","C0603X104K5RACAUTO"
"R16","4.7K_1%_0402","BottomLayer","RESC1005X40X25NL10T10","181.102","-2944.882","90",""
"R15","4.7K_1%_0402","BottomLayer","RESC1005X40X25NL10T10","86.614","-1913.386","90",""
"R5","4.7K_1%_0402","BottomLayer","RESC1005X40X25NL10T10","911.575","-169.291","0",""
"U9","RCB-F9T","TopLayer","GNSS","1382.973","-614.662","0","MOD, GPS"
"U5","DNI_MYMGK00506ERSR","TopLayer","FP-MYMGK-12-MFG","614.173","-165.354","90","DC DC CONVERTER 0.7-5V"
"U2","INA219BIDR","TopLayer","FP-D0008A-MFG","6059.055","-728.346","90","IC MONITOR PWR/CURR BIDIR 8-SOIC"
"R30","4.7K_1%_0402","TopLayer","RESC1005X40X25NL10T10","51.181","-2346.457","0",""
"R29","4.7K_1%_0402","TopLayer","RESC1005X40X25NL10T10","251.969","-2393.701","0",""
"R28","49.9R","TopLayer","RESC1608X55X25NL10T15","118.110","-2807.087","180","General Purpose Chip Resistor, 49.9 Ohm, +/- 1%, -55 to 155 degC, 0603 (1608 Metric), RoHS, Tape and Reel"
"R24","ERJ-2GE0R00X","TopLayer","RESC1005X04N","1326.772","-3523.622","0","RES, 0. OHM, 1%, 1/16W, TF, AEC-Q200, 0402"
"R23","ERJ-2GE0R00X","TopLayer","RESC1005X04N","1326.772","-3480.315","0","RES, 0. OHM, 1%, 1/16W, TF, AEC-Q200, 0402"
"R22","ERJ-3EKF4701V","BottomLayer","RESC1608X50N","2905.512","-2736.220","0","RES, 4.7K, 1%, 1/10W, TF, 0603"
"R21","CRCW080533R0FKEA","TopLayer","RESC2012X50N","5252.756","-3562.963","0","RES, 33 OHM, 1%, 1/8W, TF, 0805"
"R20","CRCW080533R0FKEA","TopLayer","RESC2012X50N","5697.638","-3566.900","0","RES, 33 OHM, 1%, 1/8W, TF, 0805"
"R19","CRCW080533R0FKEA","TopLayer","RESC2012X50N","4853.780","-3566.198","0","RES, 33 OHM, 1%, 1/8W, TF, 0805"
"R18","CRCW080533R0FKEA","TopLayer","RESC2012X50N","4408.898","-3558.324","0","RES, 33 OHM, 1%, 1/8W, TF, 0805"
"R9","20K_1%_0402","BottomLayer","RESC1005X40X25NL10T10","631.890","-57.087","0",""
"R8","2mOhm_1%_1206","TopLayer","RESC3216X89X64NL25T25","822.835","-401.575","0",""
"R7","2mOhm_1%_1206","TopLayer","RESC3216X89X64NL25T25","5949.803","-523.622","0",""
"R6","20K_1%_0402","BottomLayer","RESC1005X40X25NL10T10","549.212","-57.087","0",""
"R4","0_1%_0402","BottomLayer","RESC1005X40X25LL05T05","911.575","-131.295","180","Chip Resistor, 0 Ohm, 0.1 W, -55 to 155 degC, 0402 (1005 Metric), RoHS, Tape and Reel"
"R3","0_1%_0402","BottomLayer","RESC1005X40X25LL05T05","1106.299","-303.150","180","Chip Resistor, 0 Ohm, 0.1 W, -55 to 155 degC, 0402 (1005 Metric), RoHS, Tape and Reel"
"R2","147K_1%_0402","BottomLayer","RESC1005X40X25ML05T10","1110.236","-236.220","270",""
"R1","200_1%_0402","TopLayer","FP-ERJ2RK-IPC_A","952.756","-996.063","0","RES SMD 200 OHM 1% 1/10W 0402"
"P2","PCIex4","TopLayer","PCIE_4LANE_EDGE","2161.417","-4004.518","0","PCIE x4 Edge Connector,OrCAD Symbol,NC"
"F1","FUSE_0603_5.00A","TopLayer","FUSM1608X60N","5905.512","-381.890","270","FUSE SLOW 5.00A 32V M 0603"
"D14","155124M173200","TopLayer","155124M173200","-190.453","-1084.646","90","LED (Multiple)"
"D13","155124M173200","TopLayer","155124M173200","-190.453","-651.575","90","LED (Multiple)"
"D11","LTST-C191KGKT","TopLayer","FP-LTST-C191KGKT-MFG","287.402","-19.685","0","LED GREEN CLEAR SMD"
"D8","BAT54SW","TopLayer","SOT65P210X110-3N","5071.654","-3562.963","0","DIO, SCHOTTKY, BAT54S, DUAL SERIES, 30V, 200MA, SC-70"
"D7","BAT54SW","TopLayer","SOT65P210X110-3N","5521.457","-3560.994","0","DIO, SCHOTTKY, BAT54S, DUAL SERIES, 30V, 200MA, SC-70"
"D6","BAT54SW","TopLayer","SOT65P210X110-3N","4687.441","-3566.198","0","DIO, SCHOTTKY, BAT54S, DUAL SERIES, 30V, 200MA, SC-70"
"D5","BAT54SW","TopLayer","SOT65P210X110-3N","4239.607","-3558.324","0","DIO, SCHOTTKY, BAT54S, DUAL SERIES, 30V, 200MA, SC-70"
"D4","LTST-C191KGKT","TopLayer","FP-LTST-C191KGKT-MFG","952.756","-921.260","180","LED GREEN CLEAR SMD"
"C63","0.1uF","TopLayer","CAPC1608X87X45ML20T05","2530.816","-1178.207","270","C0603X104K5RACAUTO"
"C62","CAP_0805_10UF_25V","TopLayer","CAPC2012X14N","2624.559","-1167.323","90","CAP, CER, 10.UF, 25V, 10%, X5R, 0805"
"C61","0.1uF","BottomLayer","CAPC1608X87X45ML20T05","1254.036","-654.032","180","C0603X104K5RACAUTO"
"C60","10uF","BottomLayer","FP-MK212BG-MFG","1220.472","-362.205","180","None"
"C59","0.1uF","BottomLayer","CAPC1608X87X45ML20T05","1468.504","-803.150","0","C0603X104K5RACAUTO"
"C58","10uF","BottomLayer","FP-MK212BG-MFG","1480.328","-710.724","180","None"
"C53","CAP_0402_0.1UF_50V","BottomLayer","CAPC1005X06N","2734.410","-3806.000","90","CAP, CER, 0.1UF, 50V, 10%, X7R, AEC-Q200, 0402"
"C52","CAP_0402_0.1UF_50V","BottomLayer","CAPC1005X06N","2694.410","-3806.000","90","CAP, CER, 0.1UF, 50V, 10%, X7R, AEC-Q200, 0402"
"C51","CAP_0402_0.1UF_50V","BottomLayer","CAPC1005X06N","2569.410","-3806.000","90","CAP, CER, 0.1UF, 50V, 10%, X7R, AEC-Q200, 0402"
"C50","CAP_0402_0.1UF_50V","BottomLayer","CAPC1005X06N","2534.410","-3806.000","90","CAP, CER, 0.1UF, 50V, 10%, X7R, AEC-Q200, 0402"
"C49","CAP_0402_0.1UF_50V","BottomLayer","CAPC1005X06N","2419.410","-3806.000","90","CAP, CER, 0.1UF, 50V, 10%, X7R, AEC-Q200, 0402"
"C48","CAP_0402_0.1UF_50V","BottomLayer","CAPC1005X06N","2379.410","-3806.000","90","CAP, CER, 0.1UF, 50V, 10%, X7R, AEC-Q200, 0402"
"C47","CAP_0402_0.1UF_50V","BottomLayer","CAPC1005X06N","2226.410","-3806.000","90","CAP, CER, 0.1UF, 50V, 10%, X7R, AEC-Q200, 0402"
"C46","CAP_0402_0.1UF_50V","BottomLayer","CAPC1005X06N","2183.410","-3806.000","90","CAP, CER, 0.1UF, 50V, 10%, X7R, AEC-Q200, 0402"
"C45","CAP_0402_0.1UF_50V","BottomLayer","CAPC1005X06N","2104.410","-3806.000","90","CAP, CER, 0.1UF, 50V, 10%, X7R, AEC-Q200, 0402"
"C44","CAP_0402_0.1UF_50V","BottomLayer","CAPC1005X06N","2064.410","-3806.000","90","CAP, CER, 0.1UF, 50V, 10%, X7R, AEC-Q200, 0402"
"C22","10uF_16V_0603","BottomLayer","FP-0603-L_1_6_0_2-W_0_8_0-MFG","645.276","-559.735","90","Multilayer Ceramic Capacitor 10uF 16V X5R 20% SMD 0603 T/R"
"C21","0.1uF_25V_0402","BottomLayer","CAPC1005X56X25NL10T15","590.158","-559.735","270",""
"C20","10uF_16V_0603","BottomLayer","FP-0603-L_1_6_0_2-W_0_8_0-MFG","6110.236","-649.606","180","Multilayer Ceramic Capacitor 10uF 16V X5R 20% SMD 0603 T/R"
"C19","0.1uF_25V_0402","BottomLayer","CAPC1005X56X25NL10T15","6110.236","-598.425","0",""
"C18","0.1uF_25V_0402","BottomLayer","FP-0402-L_1_0_1-W_0_5_0_1-IPC_C","1086.614","-461.987","270","General Purpose Ceramic Capacitor, 0402, 100nF, 10%, X7R, 15%, 25V"
"C17","1uF_16V_0402","BottomLayer","FP-0402-L_1_0_0_05-W_0_5-IPC_A","956.693","-771.654","0","None"
"C16","2.2uF_16V_0402","BottomLayer","FP-C1005-050-0_05-IPC_A","960.630","-468.504","270","Multilayer Ceramic Capacitors 2.2µF ±10% 16V X5R SMD 0402"
"C15","10uF_16V_0603","BottomLayer","FP-0603-L_1_6_0_2-W_0_8_0-MFG","1019.685","-464.567","270","Multilayer Ceramic Capacitor 10uF 16V X5R 20% SMD 0603 T/R"
"C14","100uF_16V_2917","TopLayer","FP-T495D107K016ATE125-MFG","956.693","-771.654","180","CAP TANT 100UF 10% 16V 2917"
"C13","47uF_16V_1206","TopLayer","FP-C3216-160-0_2-MFG","811.116","-617.227","180","Multilayer Ceramic Capacitors 47uF ±20% 16V X5R SMD 1206"
"C12","4.7uF_50V_1206","TopLayer","FP-GRM31C-0_2-e0_3_0_8-IPC_C","307.087","-98.425","180","Chip Multilayer Ceramic Capacitors for General Purpose, 1206, 4.7uF, X7R, 15%, 10%, 50V"
"C11","4.7uF_50V_1206","TopLayer","FP-GRM31C-0_2-e0_3_0_8-IPC_C","307.087","-188.976","180","Chip Multilayer Ceramic Capacitors for General Purpose, 1206, 4.7uF, X7R, 15%, 10%, 50V"
"C10","100uF_16V_2917","TopLayer","FP-T495D107K016ATE125-MFG","606.299","125.984","0","CAP TANT 100UF 10% 16V 2917"
"C9","2.2uF_16V_0402","BottomLayer","FP-C1005-050-0_05-IPC_A","1531.496","-1015.748","270","Multilayer Ceramic Capacitors 2.2µF ±10% 16V X5R SMD 0402"
"C8","10uF_16V_0603","TopLayer","FP-0603-L_1_6_0_2-W_0_8_0-MFG","1484.252","-1015.798","270","Multilayer Ceramic Capacitor 10uF 16V X5R 20% SMD 0603 T/R"
"C7","2.2uF_16V_0402","TopLayer","FP-C1005-050-0_05-IPC_A","1681.102","-1019.685","270","Multilayer Ceramic Capacitors 2.2µF ±10% 16V X5R SMD 0402"
"C6","10uF_16V_0603","BottomLayer","FP-0603-L_1_6_0_2-W_0_8_0-MFG","1649.606","-1015.748","270","Multilayer Ceramic Capacitor 10uF 16V X5R 20% SMD 0603 T/R"
"C5","2.2uF_16V_0402","BottomLayer","FP-C1005-050-0_05-IPC_A","4157.480","-1244.094","180","Multilayer Ceramic Capacitors 2.2µF ±10% 16V X5R SMD 0402"
"C4","470uF_10V_2917","TopLayer","FP-TAJE-MFG","3464.567","-1539.370","0","470uF 10V  ±10% 500mO 2917  SMD Tantalum Capacitor"
"C3","2.2uF_16V_0402","BottomLayer","FP-C1005-050-0_05-IPC_A","1129.921","-161.417","180","Multilayer Ceramic Capacitors 2.2µF ±10% 16V X5R SMD 0402"
"C2","0.1uF","TopLayer","CAPC1608X87X45ML20T05","6118.110","-409.449","270","C0603X104K5RACAUTO"
"C1","CAP_0805_10UF_25V","TopLayer","CAPC2012X14N","6208.661","-393.701","90","CAP, CER, 10.UF, 25V, 10%, X5R, 0805"
